(kicad_pcb
	(version 20221018)
	(generator pcbnew)
	(general
    (thickness 0.908)
  )
	(paper "A4")
	(title_block
    (title "HDMI-MIPI Bridge")
    (date "2024-04-24")
    (rev "1.3.2")
		(comment 9 "footprints 5-10 of 121")
	)
	(layers
    (0 "F.Cu" signal)
    (1 "In1.Cu" signal)
    (2 "In2.Cu" signal)
    (31 "B.Cu" signal)
    (32 "B.Adhes" user "B.Adhesive")
    (33 "F.Adhes" user "F.Adhesive")
    (34 "B.Paste" user)
    (35 "F.Paste" user)
    (36 "B.SilkS" user "B.Silkscreen")
    (37 "F.SilkS" user "F.Silkscreen")
    (38 "B.Mask" user)
    (39 "F.Mask" user)
    (40 "Dwgs.User" user "User.Drawings")
    (41 "Cmts.User" user "User.Comments")
    (42 "Eco1.User" user "User.Eco1")
    (43 "Eco2.User" user "User.Eco2")
    (44 "Edge.Cuts" user)
    (45 "Margin" user)
    (46 "B.CrtYd" user "B.Courtyard")
    (47 "F.CrtYd" user "F.Courtyard")
    (48 "B.Fab" user)
    (49 "F.Fab" user)
  )
	(footprint "antmicro-footprints:R_0402_1005Metric" (layer "F.Cu")
    (at 168.1 107.95 -90)
    (descr "Resistor SMD 0402")
    (tags "resistor SMD 0402")
    (property "Author" "Antmicro")
    (property "License" "Apache-2.0")
    (property "MPN" "CR0402-FX-1002GLF")
    (property "Manufacturer" "Bourns")
    (property "Public" "False")
    (property "Sheetfile" "channel2.kicad_sch")
    (property "Sheetname" "Channel 2")
    (property "Tolerance" "1%")
    (property "Val" "10k")
    (property "ki_description" "SMD Chip Resistor, 10 kohm, ± 1%, 62.5 mW, 0402 [1005 Metric], Thick Film, General Purpose")
    (property "ki_keywords" "0402, SMT, RESISTOR, PASSIVE")
    (attr smd)
    (fp_text reference "R23" (at 1.15 -2.4 -90) (layer "F.SilkS")
        (effects (font (size 0.65 0.65) (thickness 0.13)) (justify left bottom))
    )
    (fp_text value "R_10k_0402" (at 0 1.4 -90) (layer "F.Fab")
        (effects (font (size 0.65 0.65) (thickness 0.13)) (justify left bottom))
    )
    (fp_text user "${REFERENCE}" (at -0.95 3.168 -90) (layer "F.Fab") hide
        (effects (font (size 0.7 0.7) (thickness 0.15)) (justify left bottom))
    )
    (fp_text user "Author: Antmicro" (at -0.95 4.169 -90) (layer "F.Fab") hide
        (effects (font (size 0.7 0.7) (thickness 0.15)) (justify left bottom))
    )
    (fp_text user "License: Apache-2.0" (at -0.95 5.169 -90) (layer "F.Fab") hide
        (effects (font (size 0.7 0.7) (thickness 0.15)) (justify left bottom))
    )
    (fp_rect (start -0.925 -0.47) (end 0.925 0.47)
      (stroke (width 0.05) (type default)) (fill none) (layer "F.CrtYd"))
    (fp_rect (start -0.5 -0.25) (end 0.5 0.25)
      (stroke (width 0.15) (type solid)) (fill none) (layer "F.Fab"))
    (pad "1" smd roundrect (at -0.48 0 270) (size 0.59 0.64) (layers "F.Cu" "F.Paste" "F.Mask") (roundrect_rratio 0.25)
      (net 112 "/Channel 2/HDMI2_DDC_SCL_3V3") (pintype "passive"))
    (pad "2" smd roundrect (at 0.48 0 270) (size 0.59 0.64) (layers "F.Cu" "F.Paste" "F.Mask") (roundrect_rratio 0.25)
      (net 9 "+3V3") (pintype "passive"))
  )
	(footprint "antmicro-footprints:R_0603_1608Metric" (layer "F.Cu")
    (at 168.9 103.4)
    (descr "Resistor SMD 0603")
    (tags "resistor SMD 0603")
    (property "Author" "Antmicro")
    (property "Current" "1A")
    (property "License" "Apache-2.0")
    (property "MPN" "CR0603-J/-000ELF")
    (property "Manufacturer" "Bourns")
    (property "Public" "False")
    (property "Sheetfile" "channel2.kicad_sch")
    (property "Sheetname" "Channel 2")
    (property "Tolerance" "")
    (property "Val" "0R")
    (property "ki_description" "Zero Ohm Resistor, Jumper, 0603 [1608 Metric], Thick Film, 100 mW, 1 A, Surface Mount Device, CR")
    (property "ki_keywords" "0603, SMT, RESISTOR, PASSIVE")
    (attr smd)
    (fp_text reference "R15" (at 1.1 0.35) (layer "F.SilkS")
        (effects (font (size 0.7 0.7) (thickness 0.15)) (justify left bottom))
    )
    (fp_text value "R_0R_0603" (at 0 1.6) (layer "F.Fab")
        (effects (font (size 0.7 0.7) (thickness 0.15)) (justify left bottom))
    )
    (fp_text user "License: Apache-2.0" (at -1.25 5.9) (layer "F.Fab") hide
        (effects (font (size 0.7 0.7) (thickness 0.15)) (justify left bottom))
    )
    (fp_text user "${REFERENCE}" (at -1.25 3.898) (layer "F.Fab") hide
        (effects (font (size 0.7 0.7) (thickness 0.15)) (justify left bottom))
    )
    (fp_text user "Author: Antmicro" (at -1.25 4.9) (layer "F.Fab") hide
        (effects (font (size 0.7 0.7) (thickness 0.15)) (justify left bottom))
    )
    (fp_line (start -0.15 -0.4) (end 0.15 -0.4)
      (stroke (width 0.15) (type solid)) (layer "F.SilkS"))
    (fp_line (start -0.15 0.4) (end 0.15 0.4)
      (stroke (width 0.15) (type solid)) (layer "F.SilkS"))
    (fp_rect (start -1.25 -0.65) (end 1.25 0.65)
      (stroke (width 0.05) (type solid)) (fill none) (layer "F.CrtYd"))
    (fp_rect (start -0.8 -0.4) (end 0.8 0.4)
      (stroke (width 0.15) (type solid)) (fill none) (layer "F.Fab"))
    (pad "1" smd roundrect (at -0.7 0) (size 0.8 1) (layers "F.Cu" "F.Paste" "F.Mask") (roundrect_rratio 0.2)
      (net 96 "/Channel 2/HDMI2_POWER") (pintype "passive"))
    (pad "2" smd roundrect (at 0.7 0) (size 0.8 1) (layers "F.Cu" "F.Paste" "F.Mask") (roundrect_rratio 0.2)
      (net 106 "/Channel 2/HDMI2_HPDI") (pintype "passive"))
  )
	(footprint "antmicro-footprints:C_0603_1608Metric" (layer "F.Cu")
    (at 163.94 107.03 180)
    (descr "Capacitor SMD 0603")
    (tags "capacitor 0603")
    (property "Author" "Antmicro")
    (property "Dielectric" "")
    (property "License" "Apache-2.0")
    (property "MPN" "C1608X5R1V475M080AC")
    (property "Manufacturer" "TDK")
    (property "Public" "False")
    (property "Sheetfile" "channel2.kicad_sch")
    (property "Sheetname" "Channel 2")
    (property "Val" "4u7")
    (property "Voltage" "")
    (property "ki_description" "SMD Multilayer Ceramic Capacitor, 4.7 µF, 35 V, 0603 [1608 Metric], ± 20%, X5R, C")
    (property "ki_keywords" "0603, SMT, CAPACITOR, PASSIVE, CERAMIC, MLCC")
    (attr smd)
    (fp_text reference "C52" (at 1.42 -0.15) (layer "F.SilkS")
        (effects (font (size 0.65 0.65) (thickness 0.13)) (justify right bottom))
    )
    (fp_text value "C_4u7_0603" (at 0 1.6) (layer "F.Fab")
        (effects (font (size 0.65 0.65) (thickness 0.13)) (justify right bottom))
    )
    (fp_text user "Author: Antmicro" (at -1.682 4.894) (layer "F.Fab") hide
        (effects (font (size 0.7 0.7) (thickness 0.15)) (justify right bottom))
    )
    (fp_text user "License: Apache-2.0" (at -1.682 5.895) (layer "F.Fab") hide
        (effects (font (size 0.7 0.7) (thickness 0.15)) (justify right bottom))
    )
    (fp_text user "${REFERENCE}" (at -1.682 3.895) (layer "F.Fab") hide
        (effects (font (size 0.7 0.7) (thickness 0.15)) (justify right bottom))
    )
    (fp_line (start -0.15 -0.4) (end 0.15 -0.4)
      (stroke (width 0.15) (type solid)) (layer "F.SilkS"))
    (fp_line (start -0.15 0.4) (end 0.15 0.4)
      (stroke (width 0.15) (type solid)) (layer "F.SilkS"))
    (fp_rect (start -1.25 -0.65) (end 1.25 0.65)
      (stroke (width 0.05) (type solid)) (fill none) (layer "F.CrtYd"))
    (fp_rect (start -0.8 -0.4) (end 0.8 0.4)
      (stroke (width 0.15) (type solid)) (fill none) (layer "F.Fab"))
    (pad "1" smd roundrect (at -0.7 0 180) (size 0.8 1) (layers "F.Cu" "F.Paste" "F.Mask") (roundrect_rratio 0.2)
      (net 2 "GND") (pintype "passive"))
    (pad "2" smd roundrect (at 0.7 0 180) (size 0.8 1) (layers "F.Cu" "F.Paste" "F.Mask") (roundrect_rratio 0.2)
      (net 109 "Net-(C48-Pad1)") (pintype "passive"))
  )
	(footprint "antmicro-footprints:C_0402_1005Metric" (layer "F.Cu")
    (at 155.015 109.45)
    (descr "Capacitor SMD 0402")
    (tags "capacitor SMD 0402")
    (property "Author" "Antmicro")
    (property "Dielectric" "X5R")
    (property "License" "Apache-2.0")
    (property "MPN" "GRM155R61H104KE14D")
    (property "Manufacturer" "Murata")
    (property "Public" "False")
    (property "Sheetfile" "channel2.kicad_sch")
    (property "Sheetname" "Channel 2")
    (property "Val" "100n")
    (property "Voltage" "50V")
    (property "ki_description" "SMD Multilayer Ceramic Capacitor, 0.1 µF, 50 V, 0402 [1005 Metric], ± 10%, X5R, GRM Series")
    (property "ki_keywords" "0402, SMT, CAPACITOR, PASSIVE, CERAMIC, MLCC")
    (attr smd)
    (fp_text reference "C34" (at -1.515 7.55) (layer "F.SilkS")
        (effects (font (size 0.65 0.65) (thickness 0.13)) (justify left bottom))
    )
    (fp_text value "C_100n_0402" (at 0 1.4) (layer "F.Fab")
        (effects (font (size 0.65 0.65) (thickness 0.13)) (justify left bottom))
    )
    (fp_text user "${REFERENCE}" (at -0.932 3.168) (layer "F.Fab") hide
        (effects (font (size 0.7 0.7) (thickness 0.15)) (justify left bottom))
    )
    (fp_text user "Author: Antmicro" (at -0.932 4.17) (layer "F.Fab") hide
        (effects (font (size 0.7 0.7) (thickness 0.15)) (justify left bottom))
    )
    (fp_text user "License: Apache-2.0" (at -0.932 5.17) (layer "F.Fab") hide
        (effects (font (size 0.7 0.7) (thickness 0.15)) (justify left bottom))
    )
    (fp_rect (start -0.925 -0.47) (end 0.925 0.47)
      (stroke (width 0.05) (type default)) (fill none) (layer "F.CrtYd"))
    (fp_line (start -0.494 -0.25) (end 0.504 -0.25)
      (stroke (width 0.15) (type solid)) (layer "F.Fab"))
    (fp_line (start -0.494 0.248) (end -0.494 -0.25)
      (stroke (width 0.15) (type solid)) (layer "F.Fab"))
    (fp_line (start 0.504 -0.25) (end 0.504 0.248)
      (stroke (width 0.15) (type solid)) (layer "F.Fab"))
    (fp_line (start 0.504 0.248) (end -0.494 0.248)
      (stroke (width 0.15) (type solid)) (layer "F.Fab"))
    (pad "1" smd roundrect (at -0.48 0) (size 0.59 0.64) (layers "F.Cu" "F.Paste" "F.Mask") (roundrect_rratio 0.25)
      (net 2 "GND") (pintype "passive"))
    (pad "2" smd roundrect (at 0.48 0) (size 0.59 0.64) (layers "F.Cu" "F.Paste" "F.Mask") (roundrect_rratio 0.25)
      (net 108 "/Channel 2/CH2_AVDD33") (pintype "passive"))
  )
	(footprint "antmicro-footprints:Oscillator_SMD_TXC_7C_5x3.2x1.2mm" (layer "F.Cu")
    (at 150.81 110.06)
    (property "Author" "Antmicro")
    (property "License" "Apache-2.0")
    (property "MPN" "7C-27.000MBB-T")
    (property "Manufacturer" "TXC")
    (property "Public" "False")
    (property "Sheetfile" "channel2.kicad_sch")
    (property "Sheetname" "Channel 2")
    (property "Val" "27 MHz")
    (property "ki_description" "Oscillator, 27 MHz, 50 ppm, SMT, 5mm x 3.2mm, 3.3 V, 7C Series")
    (property "ki_keywords" "OSCILLATOR")
    (attr smd)
    (fp_text reference "Y2" (at 1.53 3.65 180) (layer "F.SilkS")
        (effects (font (size 0.65 0.65) (thickness 0.13)) (justify right bottom))
    )
    (fp_text value "Oscillator_27MHz_TXC_7C" (at -4.1148 3.4544) (layer "F.Fab")
        (effects (font (size 0.65 0.65) (thickness 0.13)) (justify left bottom))
    )
    (fp_text user "License: Apache-2.0" (at -2.668 7.972) (layer "F.Fab") hide
        (effects (font (size 0.7 0.7) (thickness 0.15)) (justify left bottom))
    )
    (fp_text user "${REFERENCE}" (at -2.668 5.573) (layer "F.Fab") hide
        (effects (font (size 0.7 0.7) (thickness 0.15)) (justify left bottom))
    )
    (fp_text user "Author: Antmicro" (at -2.668 6.773) (layer "F.Fab") hide
        (effects (font (size 0.7 0.7) (thickness 0.15)) (justify left bottom))
    )
    (fp_line (start -1.7 1.1) (end -1.7 -1.1)
      (stroke (width 0.12) (type solid)) (layer "F.SilkS"))
    (fp_line (start -0.4 -2.6) (end 0.4 -2.6)
      (stroke (width 0.12) (type solid)) (layer "F.SilkS"))
    (fp_line (start -0.4 2.6) (end 0.4 2.6)
      (stroke (width 0.12) (type solid)) (layer "F.SilkS"))
    (fp_line (start 1.7 1.1) (end 1.7 -1.1)
      (stroke (width 0.12) (type solid)) (layer "F.SilkS"))
    (fp_circle (center -1.8438 -2.2532) (end -1.8438 -2.2032)
      (stroke (width 0.15) (type solid)) (fill solid) (layer "F.SilkS"))
    (fp_rect (start -1.9 -2.85) (end 1.9 2.8)
      (stroke (width 0.05) (type solid)) (fill none) (layer "F.CrtYd"))
    (pad "1" smd rect (at -1.099 -1.9 270) (size 1.4 1.2) (layers "F.Cu" "F.Paste" "F.Mask")
      (net 30 "Net-(Y2-EN)") (pinfunction "EN") (pintype "input"))
    (pad "2" smd rect (at -1.1 1.9 270) (size 1.4 1.2) (layers "F.Cu" "F.Paste" "F.Mask")
      (net 2 "GND") (pinfunction "GND") (pintype "power_in"))
    (pad "3" smd rect (at 1.099 1.9 270) (size 1.4 1.2) (layers "F.Cu" "F.Paste" "F.Mask")
      (net 31 "Net-(Y2-OUT)") (pinfunction "OUT") (pintype "output"))
    (pad "4" smd rect (at 1.1 -1.9 270) (size 1.4 1.2) (layers "F.Cu" "F.Paste" "F.Mask")
      (net 30 "Net-(Y2-EN)") (pinfunction "VDD") (pintype "power_in"))
  )
	(footprint "antmicro-footprints:C_0603_1608Metric" (layer "F.Cu")
    (at 169.2 115.7 -90)
    (descr "Capacitor SMD 0603")
    (tags "capacitor 0603")
    (property "Author" "Antmicro")
    (property "Dielectric" "template_dielectric")
    (property "License" "Apache-2.0")
    (property "MPN" "GRM188R61A106KE69D")
    (property "Manufacturer" "Murata")
    (property "Public" "False")
    (property "Sheetfile" "channel2.kicad_sch")
    (property "Sheetname" "Channel 2")
    (property "Val" "10u")
    (property "Voltage" "")
    (property "ki_description" "SMD Multilayer Ceramic Capacitor, 10 µF, 10 V, 0603 [1608 Metric], ± 10%, X5R, GRM Series")
    (property "ki_keywords" "0603, SMT, CAPACITOR, PASSIVE, CERAMIC, MLCC")
    (attr smd)
    (fp_text reference "C43" (at -3.3 -0.4 90) (layer "F.SilkS")
        (effects (font (size 0.65 0.65) (thickness 0.13)) (justify right bottom))
    )
    (fp_text value "C_10u_0603" (at 0 1.6 90) (layer "F.Fab")
        (effects (font (size 0.65 0.65) (thickness 0.13)) (justify right bottom))
    )
    (fp_text user "Author: Antmicro" (at -1.682 4.894 90) (layer "F.Fab") hide
        (effects (font (size 0.7 0.7) (thickness 0.15)) (justify right bottom))
    )
    (fp_text user "${REFERENCE}" (at -1.682 3.895 90) (layer "F.Fab") hide
        (effects (font (size 0.7 0.7) (thickness 0.15)) (justify right bottom))
    )
    (fp_text user "License: Apache-2.0" (at -1.682 5.895 90) (layer "F.Fab") hide
        (effects (font (size 0.7 0.7) (thickness 0.15)) (justify right bottom))
    )
    (fp_line (start -0.15 -0.4) (end 0.15 -0.4)
      (stroke (width 0.15) (type solid)) (layer "F.SilkS"))
    (fp_line (start -0.15 0.4) (end 0.15 0.4)
      (stroke (width 0.15) (type solid)) (layer "F.SilkS"))
    (fp_rect (start -1.25 -0.65) (end 1.25 0.65)
      (stroke (width 0.05) (type solid)) (fill none) (layer "F.CrtYd"))
    (fp_rect (start -0.8 -0.4) (end 0.8 0.4)
      (stroke (width 0.15) (type solid)) (fill none) (layer "F.Fab"))
    (pad "1" smd roundrect (at -0.7 0 270) (size 0.8 1) (layers "F.Cu" "F.Paste" "F.Mask") (roundrect_rratio 0.2)
      (net 2 "GND") (pintype "passive"))
    (pad "2" smd roundrect (at 0.7 0 270) (size 0.8 1) (layers "F.Cu" "F.Paste" "F.Mask") (roundrect_rratio 0.2)
      (net 25 "CH2_1V2") (pintype "passive"))
  )
)
